# T6G (Grand Teton) — schematic netlist excerpt (pin names and nets, part order shuffled) for the footprints in the layout excerpt that follows; sources: Cadence DE-HDL packaged netlist, KiCad conversion of 04192023_DAF0TMB3IC0_F0TG_MB_C_brd_V02_OCP.brd

R914  Q_RES  0 5% CHIP  pkg 0201LF  page 353 : A = SMB_RT_CPU1_P3_R_SDA ; B = SMB_RT_CPU1_P3_R2_SDA
R1212  Q_RES  1K 1% CHIP  pkg 0201LF  page 186 : A = GND ; B = RT_ROM_MUX3_OE_N
R888  Q_RES  10K 5% EMPTY  pkg 0402LF  page 151 : A = P3V3_AUX ; B = SCM_SPARE_0

(kicad_pcb
	(version 20260206)
	(generator "pcbnew")
	(generator_version "10.0")
	(general
		(thickness 1.6)
		(legacy_teardrops no)
	)
	(paper "A4")
	(title_block
		(title "04192023_DAF0TMB3IC0_F0TG_MB_C_brd_V02_OCP.brd")
		(comment 1 "Grand Teton / footprints 8135-8137 of 8354")
	)
	(layers
		(0 "F.Cu" signal "TOP")
		(4 "In1.Cu" signal "GND")
		(6 "In2.Cu" signal "IN1")
		(8 "In3.Cu" signal "GND1")
		(10 "In4.Cu" signal "IN2")
		(12 "In5.Cu" signal "GND2")
		(14 "In6.Cu" signal "IN3")
		(16 "In7.Cu" signal "GND3")
		(18 "In8.Cu" signal "VCC")
		(20 "In9.Cu" signal "VCC1")
		(22 "In10.Cu" signal "GND4")
		(24 "In11.Cu" signal "IN4")
		(26 "In12.Cu" signal "GND5")
		(28 "In13.Cu" signal "IN5")
		(30 "In14.Cu" signal "GND6")
		(32 "In15.Cu" signal "IN6")
		(34 "In16.Cu" signal "GND7")
		(2 "B.Cu" signal "BOTTOM")
		(9 "F.Adhes" user "F.Adhesive")
		(11 "B.Adhes" user "B.Adhesive")
		(13 "F.Paste" user "Package Geometry/Pastemask Top")
		(15 "B.Paste" user "Package Geometry/Pastemask Bottom")
		(5 "F.SilkS" user "Ref Des/Silkscreen Top")
		(7 "B.SilkS" user "Ref Des/Silkscreen Bottom")
		(1 "F.Mask" user "Board Geometry/Soldermask Top")
		(3 "B.Mask" user "Board Geometry/Soldermask Bottom")
		(17 "Dwgs.User" user "User.Drawings")
		(19 "Cmts.User" user "User.Comments")
		(21 "Eco1.User" user "User.Eco1")
		(23 "Eco2.User" user "User.Eco2")
		(25 "Edge.Cuts" user "Board Geometry/Outline")
		(27 "Margin" user)
		(31 "F.CrtYd" user "Package Geometry/Place Bound Top")
		(29 "B.CrtYd" user "Package Geometry/Place Bound Bottom")
		(35 "F.Fab" user "Ref Des/Assembly Top")
		(33 "B.Fab" user "Ref Des/Assembly Bottom")
	)
	(footprint ""
		(layer "B.Cu")
		(at 167.132 -116.296948 180)
		(property "Reference" "R888"
			(at 0 0 0)
			(layer "B.SilkS")
			(hide yes)
			(effects
				(font
					(size 1.27 1.27)
				)
				(justify mirror)
			)
		)
		(property "Value" ""
			(at 0 0 0)
			(layer "B.Fab")
			(effects
				(font
					(size 1.27 1.27)
				)
				(justify mirror)
			)
		)
		(duplicate_pad_numbers_are_jumpers no)
		(fp_line
			(start 0.7874 0.4064)
			(end 0.7874 -0.4064)
			(stroke
				(width 0.1524)
				(type default)
			)
			(layer "B.SilkS")
		)
		(fp_line
			(start 0.7874 -0.4064)
			(end -0.7874 -0.4064)
			(stroke
				(width 0.1524)
				(type default)
			)
			(layer "B.SilkS")
		)
		(fp_line
			(start -0.7874 0.4064)
			(end 0.7874 0.4064)
			(stroke
				(width 0.1524)
				(type default)
			)
			(layer "B.SilkS")
		)
		(fp_line
			(start -0.7874 -0.4064)
			(end -0.7874 0.4064)
			(stroke
				(width 0.1524)
				(type default)
			)
			(layer "B.SilkS")
		)
		(fp_line
			(start 0.67945 0.3048)
			(end 0.67945 -0.305054)
			(stroke
				(width 0.1)
				(type default)
			)
			(layer "B.Fab")
		)
		(fp_line
			(start 0.67945 -0.305054)
			(end 0.12065 -0.305054)
			(stroke
				(width 0.1)
				(type default)
			)
			(layer "B.Fab")
		)
		(fp_line
			(start 0.12065 0.3048)
			(end 0.67945 0.3048)
			(stroke
				(width 0.1)
				(type default)
			)
			(layer "B.Fab")
		)
		(fp_line
			(start 0.12065 0.2794)
			(end 0.12065 0.3048)
			(stroke
				(width 0.1)
				(type default)
			)
			(layer "B.Fab")
		)
		(fp_line
			(start 0.12065 -0.2794)
			(end -0.12065 -0.2794)
			(stroke
				(width 0.1)
				(type default)
			)
			(layer "B.Fab")
		)
		(fp_line
			(start 0.12065 -0.305054)
			(end 0.12065 -0.2794)
			(stroke
				(width 0.1)
				(type default)
			)
			(layer "B.Fab")
		)
		(fp_line
			(start -0.120396 0.3048)
			(end -0.120396 0.2794)
			(stroke
				(width 0.1)
				(type default)
			)
			(layer "B.Fab")
		)
		(fp_line
			(start -0.120396 0.2794)
			(end 0.12065 0.2794)
			(stroke
				(width 0.1)
				(type default)
			)
			(layer "B.Fab")
		)
		(fp_line
			(start -0.12065 -0.2794)
			(end -0.12065 -0.3048)
			(stroke
				(width 0.1)
				(type default)
			)
			(layer "B.Fab")
		)
		(fp_line
			(start -0.12065 -0.3048)
			(end -0.67945 -0.3048)
			(stroke
				(width 0.1)
				(type default)
			)
			(layer "B.Fab")
		)
		(fp_line
			(start -0.67945 0.3048)
			(end -0.120396 0.3048)
			(stroke
				(width 0.1)
				(type default)
			)
			(layer "B.Fab")
		)
		(fp_line
			(start -0.67945 -0.3048)
			(end -0.67945 0.3048)
			(stroke
				(width 0.1)
				(type default)
			)
			(layer "B.Fab")
		)
		(pad "1" smd circle
			(at 0.40005 0)
			(size 0 0)
			(layers "B.Cu" "B.Mask" "B.Paste")
			(net "P3V3_AUX")
		)
		(pad "2" smd circle
			(at -0.40005 0)
			(size 0 0)
			(layers "B.Cu" "B.Mask" "B.Paste")
			(net "SCM_SPARE_0")
		)
	)
	(footprint ""
		(layer "B.Cu")
		(at 214.122 -338.582)
		(property "Reference" "R914"
			(at 0 0 0)
			(layer "B.SilkS")
			(hide yes)
			(effects
				(font
					(size 1.27 1.27)
				)
				(justify mirror)
			)
		)
		(property "Value" ""
			(at 0 0 0)
			(layer "B.Fab")
			(effects
				(font
					(size 1.27 1.27)
				)
				(justify mirror)
			)
		)
		(duplicate_pad_numbers_are_jumpers no)
		(fp_line
			(start -0.32512 -0.175006)
			(end -0.32512 0.175006)
			(stroke
				(width 0.1)
				(type default)
			)
			(layer "B.Fab")
		)
		(fp_line
			(start -0.32512 0.175006)
			(end 0.32512 0.175006)
			(stroke
				(width 0.1)
				(type default)
			)
			(layer "B.Fab")
		)
		(fp_line
			(start 0.32512 -0.175006)
			(end -0.32512 -0.175006)
			(stroke
				(width 0.1)
				(type default)
			)
			(layer "B.Fab")
		)
		(fp_line
			(start 0.32512 0.175006)
			(end 0.32512 -0.175006)
			(stroke
				(width 0.1)
				(type default)
			)
			(layer "B.Fab")
		)
		(pad "1" smd rect
			(at 0.2667 0 180)
			(size 0.3048 0.381)
			(layers "B.Cu" "B.Mask" "B.Paste")
			(net "SMB_RT_CPU1_P3_R_SDA")
		)
		(pad "2" smd rect
			(at -0.2667 0)
			(size 0.3048 0.381)
			(layers "B.Cu" "B.Mask" "B.Paste")
			(net "SMB_RT_CPU1_P3_R2_SDA")
		)
	)
	(footprint ""
		(layer "B.Cu")
		(at 166.473124 -424.821604 -90)
		(property "Reference" "R1212"
			(at 0 0 90)
			(layer "B.SilkS")
			(hide yes)
			(effects
				(font
					(size 1.27 1.27)
				)
				(justify mirror)
			)
		)
		(property "Value" ""
			(at 0 0 90)
			(layer "B.Fab")
			(effects
				(font
					(size 1.27 1.27)
				)
				(justify mirror)
			)
		)
		(duplicate_pad_numbers_are_jumpers no)
		(fp_line
			(start -0.32512 0.175006)
			(end 0.32512 0.175006)
			(stroke
				(width 0.1)
				(type default)
			)
			(layer "B.Fab")
		)
		(fp_line
			(start 0.32512 0.175006)
			(end 0.32512 -0.175006)
			(stroke
				(width 0.1)
				(type default)
			)
			(layer "B.Fab")
		)
		(fp_line
			(start -0.32512 -0.175006)
			(end -0.32512 0.175006)
			(stroke
				(width 0.1)
				(type default)
			)
			(layer "B.Fab")
		)
		(fp_line
			(start 0.32512 -0.175006)
			(end -0.32512 -0.175006)
			(stroke
				(width 0.1)
				(type default)
			)
			(layer "B.Fab")
		)
		(pad "1" smd rect
			(at 0.2667 0 90)
			(size 0.3048 0.381)
			(layers "B.Cu" "B.Mask" "B.Paste")
			(net "GND")
		)
		(pad "2" smd rect
			(at -0.2667 0 270)
			(size 0.3048 0.381)
			(layers "B.Cu" "B.Mask" "B.Paste")
			(net "RT_ROM_MUX3_OE_N")
		)
	)
)
